# T6G (Grand Teton) — schematic netlist excerpt (pin names and nets, part order shuffled) for the footprints in the layout excerpt that follows; sources: Cadence DE-HDL packaged netlist, KiCad conversion of 04192023_DAF0TMB3IC0_F0TG_MB_C_brd_V02_OCP.brd

U4  PI3CSW12ZUAEX  IC  pkg UQFN10_0-5_2X1-5  page 161
  \1d+\  = SMB_APML_CPU0_MUX2_SCL
  \1d-\  = SMB_APML_CPU0_MUX2_SDA
  \2d+\  = SMB_APML_CPU1_MUX2_SCL
  \2d-\  = SMB_APML_CPU1_MUX2_SDA
  GND  = GND
  \oe#\  = FM_APML_MUX2_OE_N
  \d-\  = SMB_CPU0_CPU1_APML_MUX2_SDA
  \d+\  = SMB_CPU0_CPU1_APML_MUX2_SCL
  S  = FM_APML_MUX2_SEL
  VDD  = P3V3_AUX

R8104  Q_RES  0 5% EMPTY  pkg 0402LF  page 242 : A = FM_AC_PWR_BTN_R_N ; B = FM_AC_PWR_BTN_PLD_N

(kicad_pcb
	(version 20260206)
	(generator "pcbnew")
	(generator_version "10.0")
	(general
		(thickness 1.6)
		(legacy_teardrops no)
	)
	(paper "A4")
	(title_block
		(title "04192023_DAF0TMB3IC0_F0TG_MB_C_brd_V02_OCP.brd")
		(comment 1 "Grand Teton / footprints 5613-5614 of 8354")
	)
	(layers
		(0 "F.Cu" signal "TOP")
		(4 "In1.Cu" signal "GND")
		(6 "In2.Cu" signal "IN1")
		(8 "In3.Cu" signal "GND1")
		(10 "In4.Cu" signal "IN2")
		(12 "In5.Cu" signal "GND2")
		(14 "In6.Cu" signal "IN3")
		(16 "In7.Cu" signal "GND3")
		(18 "In8.Cu" signal "VCC")
		(20 "In9.Cu" signal "VCC1")
		(22 "In10.Cu" signal "GND4")
		(24 "In11.Cu" signal "IN4")
		(26 "In12.Cu" signal "GND5")
		(28 "In13.Cu" signal "IN5")
		(30 "In14.Cu" signal "GND6")
		(32 "In15.Cu" signal "IN6")
		(34 "In16.Cu" signal "GND7")
		(2 "B.Cu" signal "BOTTOM")
		(9 "F.Adhes" user "F.Adhesive")
		(11 "B.Adhes" user "B.Adhesive")
		(13 "F.Paste" user "Package Geometry/Pastemask Top")
		(15 "B.Paste" user "Package Geometry/Pastemask Bottom")
		(5 "F.SilkS" user "Ref Des/Silkscreen Top")
		(7 "B.SilkS" user "Ref Des/Silkscreen Bottom")
		(1 "F.Mask" user "Board Geometry/Soldermask Top")
		(3 "B.Mask" user "Board Geometry/Soldermask Bottom")
		(17 "Dwgs.User" user "User.Drawings")
		(19 "Cmts.User" user "User.Comments")
		(21 "Eco1.User" user "User.Eco1")
		(23 "Eco2.User" user "User.Eco2")
		(25 "Edge.Cuts" user "Board Geometry/Outline")
		(27 "Margin" user)
		(31 "F.CrtYd" user "Package Geometry/Place Bound Top")
		(29 "B.CrtYd" user "Package Geometry/Place Bound Bottom")
		(35 "F.Fab" user "Ref Des/Assembly Top")
		(33 "B.Fab" user "Ref Des/Assembly Bottom")
	)
	(footprint ""
		(layer "B.Cu")
		(at 232.857802 -248.53265)
		(property "Reference" "U4"
			(at 1.58496 -2.89687 0)
			(unlocked yes)
			(layer "B.SilkS")
			(effects
				(font
					(size 0.7874 0.5842)
					(thickness 0.1524)
				)
				(justify mirror)
			)
		)
		(property "Value" ""
			(at 0 0 0)
			(layer "B.Fab")
			(effects
				(font
					(size 1.27 1.27)
				)
				(justify mirror)
			)
		)
		(duplicate_pad_numbers_are_jumpers no)
		(fp_line
			(start -1.03378 -1.284478)
			(end -1.03378 1.284478)
			(stroke
				(width 0.1524)
				(type default)
			)
			(layer "B.SilkS")
		)
		(fp_line
			(start -1.03378 1.284478)
			(end 1.03378 1.284478)
			(stroke
				(width 0.1524)
				(type default)
			)
			(layer "B.SilkS")
		)
		(fp_line
			(start 1.03378 -1.284478)
			(end -1.03378 -1.284478)
			(stroke
				(width 0.1524)
				(type default)
			)
			(layer "B.SilkS")
		)
		(fp_line
			(start 1.03378 1.284478)
			(end 1.03378 -1.284478)
			(stroke
				(width 0.1524)
				(type default)
			)
			(layer "B.SilkS")
		)
		(fp_poly
			(pts
				(xy 1.806702 -1.052576) (xy 1.806702 -0.447548) (xy 1.201674 -0.750062)
			)
			(stroke
				(width 0)
				(type default)
			)
			(fill yes)
			(layer "B.SilkS")
		)
		(fp_line
			(start -0.774954 -1.02489)
			(end -0.774954 1.02489)
			(stroke
				(width 0.1)
				(type default)
			)
			(layer "B.Fab")
		)
		(fp_line
			(start -0.774954 1.02489)
			(end 0.774954 1.02489)
			(stroke
				(width 0.1)
				(type default)
			)
			(layer "B.Fab")
		)
		(fp_line
			(start 0.774954 -1.02489)
			(end -0.774954 -1.02489)
			(stroke
				(width 0.1)
				(type default)
			)
			(layer "B.Fab")
		)
		(fp_line
			(start 0.774954 1.02489)
			(end 0.774954 -1.02489)
			(stroke
				(width 0.1)
				(type default)
			)
			(layer "B.Fab")
		)
		(fp_poly
			(pts
				(xy 1.201674 -0.750062) (xy 1.806702 -0.447548) (xy 1.806702 -1.052576)
			)
			(stroke
				(width 0)
				(type default)
			)
			(fill yes)
			(layer "B.Fab")
		)
		(pad "1" smd rect
			(at 0.64008 -0.750062 90)
			(size 0.3048 0.5334)
			(layers "B.Cu" "B.Mask" "B.Paste")
			(net "SMB_APML_CPU0_MUX2_SCL")
		)
		(pad "2" smd rect
			(at 0.64008 -0.249936 90)
			(size 0.254 0.5334)
			(layers "B.Cu" "B.Mask" "B.Paste")
			(net "SMB_APML_CPU0_MUX2_SDA")
		)
		(pad "3" smd rect
			(at 0.64008 0.249936 90)
			(size 0.254 0.5334)
			(layers "B.Cu" "B.Mask" "B.Paste")
			(net "SMB_APML_CPU1_MUX2_SCL")
		)
		(pad "4" smd rect
			(at 0.64008 0.750062 90)
			(size 0.3048 0.5334)
			(layers "B.Cu" "B.Mask" "B.Paste")
			(net "SMB_APML_CPU1_MUX2_SDA")
		)
		(pad "5" smd rect
			(at 0 0.839978 180)
			(size 0.3302 0.635)
			(layers "B.Cu" "B.Mask" "B.Paste")
			(net "GND")
		)
		(pad "6" smd rect
			(at -0.64008 0.750062 90)
			(size 0.3048 0.5334)
			(layers "B.Cu" "B.Mask" "B.Paste")
			(net "FM_APML_MUX2_OE_N")
		)
		(pad "7" smd rect
			(at -0.64008 0.249936 90)
			(size 0.254 0.5334)
			(layers "B.Cu" "B.Mask" "B.Paste")
			(net "SMB_CPU0_CPU1_APML_MUX2_SDA")
		)
		(pad "8" smd rect
			(at -0.64008 -0.249936 90)
			(size 0.254 0.5334)
			(layers "B.Cu" "B.Mask" "B.Paste")
			(net "SMB_CPU0_CPU1_APML_MUX2_SCL")
		)
		(pad "9" smd rect
			(at -0.64008 -0.750062 90)
			(size 0.3048 0.5334)
			(layers "B.Cu" "B.Mask" "B.Paste")
			(net "FM_APML_MUX2_SEL")
		)
		(pad "10" smd rect
			(at 0 -0.839978 180)
			(size 0.3302 0.635)
			(layers "B.Cu" "B.Mask" "B.Paste")
			(net "P3V3_AUX")
		)
	)
	(footprint ""
		(layer "B.Cu")
		(at 200.406 -144.272 90)
		(property "Reference" "R8104"
			(at 0 0 90)
			(layer "B.SilkS")
			(hide yes)
			(effects
				(font
					(size 1.27 1.27)
				)
				(justify mirror)
			)
		)
		(property "Value" ""
			(at 0 0 90)
			(layer "B.Fab")
			(effects
				(font
					(size 1.27 1.27)
				)
				(justify mirror)
			)
		)
		(duplicate_pad_numbers_are_jumpers no)
		(fp_line
			(start 0.7874 -0.4064)
			(end -0.7874 -0.4064)
			(stroke
				(width 0.1524)
				(type default)
			)
			(layer "B.SilkS")
		)
		(fp_line
			(start -0.7874 -0.4064)
			(end -0.7874 0.4064)
			(stroke
				(width 0.1524)
				(type default)
			)
			(layer "B.SilkS")
		)
		(fp_line
			(start 0.7874 0.4064)
			(end 0.7874 -0.4064)
			(stroke
				(width 0.1524)
				(type default)
			)
			(layer "B.SilkS")
		)
		(fp_line
			(start -0.7874 0.4064)
			(end 0.7874 0.4064)
			(stroke
				(width 0.1524)
				(type default)
			)
			(layer "B.SilkS")
		)
		(fp_line
			(start 0.67945 -0.305054)
			(end 0.12065 -0.305054)
			(stroke
				(width 0.1)
				(type default)
			)
			(layer "B.Fab")
		)
		(fp_line
			(start 0.12065 -0.305054)
			(end 0.12065 -0.2794)
			(stroke
				(width 0.1)
				(type default)
			)
			(layer "B.Fab")
		)
		(fp_line
			(start -0.12065 -0.3048)
			(end -0.67945 -0.3048)
			(stroke
				(width 0.1)
				(type default)
			)
			(layer "B.Fab")
		)
		(fp_line
			(start -0.67945 -0.3048)
			(end -0.67945 0.3048)
			(stroke
				(width 0.1)
				(type default)
			)
			(layer "B.Fab")
		)
		(fp_line
			(start 0.12065 -0.2794)
			(end -0.12065 -0.2794)
			(stroke
				(width 0.1)
				(type default)
			)
			(layer "B.Fab")
		)
		(fp_line
			(start -0.12065 -0.2794)
			(end -0.12065 -0.3048)
			(stroke
				(width 0.1)
				(type default)
			)
			(layer "B.Fab")
		)
		(fp_line
			(start 0.12065 0.2794)
			(end 0.12065 0.3048)
			(stroke
				(width 0.1)
				(type default)
			)
			(layer "B.Fab")
		)
		(fp_line
			(start -0.120396 0.2794)
			(end 0.12065 0.2794)
			(stroke
				(width 0.1)
				(type default)
			)
			(layer "B.Fab")
		)
		(fp_line
			(start 0.67945 0.3048)
			(end 0.67945 -0.305054)
			(stroke
				(width 0.1)
				(type default)
			)
			(layer "B.Fab")
		)
		(fp_line
			(start 0.12065 0.3048)
			(end 0.67945 0.3048)
			(stroke
				(width 0.1)
				(type default)
			)
			(layer "B.Fab")
		)
		(fp_line
			(start -0.120396 0.3048)
			(end -0.120396 0.2794)
			(stroke
				(width 0.1)
				(type default)
			)
			(layer "B.Fab")
		)
		(fp_line
			(start -0.67945 0.3048)
			(end -0.120396 0.3048)
			(stroke
				(width 0.1)
				(type default)
			)
			(layer "B.Fab")
		)
		(pad "1" smd circle
			(at 0.40005 0 270)
			(size 0 0)
			(layers "B.Cu" "B.Mask" "B.Paste")
			(net "FM_AC_PWR_BTN_R_N")
		)
		(pad "2" smd circle
			(at -0.40005 0 270)
			(size 0 0)
			(layers "B.Cu" "B.Mask" "B.Paste")
			(net "FM_AC_PWR_BTN_PLD_N")
		)
	)
)
